(kicad_pcb
	(version 20260206)
	(generator "pcbnew")
	(generator_version "10.0")
	(general
		(thickness 1.6)
		(legacy_teardrops no)
	)
	(paper "A4")
	(title_block
		(title "Bryce Canyon_R.DPB_16317-1_OCP.brd")
		(comment 1 "Bryce Canyon / footprints 808-814 of 2099")
	)
	(layers
		(0 "F.Cu" signal "TOP")
		(4 "In1.Cu" signal "L2GND")
		(6 "In2.Cu" signal "L3")
		(8 "In3.Cu" signal "L4VCC")
		(10 "In4.Cu" signal "L5VCC")
		(12 "In5.Cu" signal "L6")
		(14 "In6.Cu" signal "L7GND")
		(2 "B.Cu" signal "BOTTOM")
		(9 "F.Adhes" user "F.Adhesive")
		(11 "B.Adhes" user "B.Adhesive")
		(13 "F.Paste" user "Package Geometry/Pastemask Top")
		(15 "B.Paste" user "Package Geometry/Pastemask Bottom")
		(5 "F.SilkS" user "Ref Des/Silkscreen Top")
		(7 "B.SilkS" user "Ref Des/Silkscreen Bottom")
		(1 "F.Mask" user "Board Geometry/Soldermask Top")
		(3 "B.Mask" user "Board Geometry/Soldermask Bottom")
		(17 "Dwgs.User" user "User.Drawings")
		(19 "Cmts.User" user "User.Comments")
		(21 "Eco1.User" user "User.Eco1")
		(23 "Eco2.User" user "User.Eco2")
		(25 "Edge.Cuts" user "Board Geometry/Outline")
		(27 "Margin" user)
		(31 "F.CrtYd" user "Package Geometry/Place Bound Top")
		(29 "B.CrtYd" user "Package Geometry/Place Bound Bottom")
		(35 "F.Fab" user "Ref Des/Assembly Top")
		(33 "B.Fab" user "Ref Des/Assembly Bottom")
	)
	(footprint ""
		(layer "F.Cu")
		(at 214.4522 -192.786 -90)
		(property "Reference" "U4"
			(at 0 0 270)
			(layer "F.SilkS")
			(hide yes)
			(effects
				(font
					(size 1.27 1.27)
				)
			)
		)
		(property "Value" "TCA9555PWR-GP"
			(at 0 -6.9342 270)
			(unlocked yes)
			(layer "F.Fab")
			(hide yes)
			(effects
				(font
					(size 1.016 1.016)
					(thickness 0.1524)
				)
			)
		)
		(property "Device Type" "TSOIC24H48"
			(at 0 -8.5852 270)
			(unlocked yes)
			(layer "F.Fab")
			(hide yes)
			(effects
				(font
					(size 1.016 1.016)
					(thickness 0.1524)
				)
			)
		)
		(duplicate_pad_numbers_are_jumpers no)
		(fp_line
			(start -4.2291 3.937)
			(end -4.2291 -1.397)
			(stroke
				(width 0.1524)
				(type default)
			)
			(layer "F.SilkS")
		)
		(fp_line
			(start -4.22656 3.81)
			(end -4.2291 1.397)
			(stroke
				(width 0.508)
				(type default)
			)
			(layer "F.SilkS")
		)
		(fp_line
			(start 3.81 1.397)
			(end -4.2291 1.397)
			(stroke
				(width 0.1524)
				(type default)
			)
			(layer "F.SilkS")
		)
		(fp_line
			(start -3.429 0)
			(end -4.2291 0.8001)
			(stroke
				(width 0.1524)
				(type default)
			)
			(layer "F.SilkS")
		)
		(fp_line
			(start -4.2291 -0.8001)
			(end -3.429 0)
			(stroke
				(width 0.1524)
				(type default)
			)
			(layer "F.SilkS")
		)
		(fp_line
			(start -4.2291 -1.397)
			(end 3.81 -1.397)
			(stroke
				(width 0.1524)
				(type default)
			)
			(layer "F.SilkS")
		)
		(fp_line
			(start 3.81 -1.397)
			(end 3.81 1.397)
			(stroke
				(width 0.1524)
				(type default)
			)
			(layer "F.SilkS")
		)
		(fp_poly
			(pts
				(xy -3.90652 -1.8542) (xy 3.90652 -1.8542) (xy 3.90652 1.8542) (xy -3.90652 1.8542)
			)
			(stroke
				(width 0)
				(type default)
			)
			(fill yes)
			(layer "F.SilkS")
		)
		(fp_poly
			(pts
				(xy -4.2164 3.81) (xy 4.2164 3.81) (xy 4.22656 -3.81) (xy -4.2164 -3.81)
			)
			(stroke
				(width 0)
				(type default)
			)
			(fill no)
			(layer "F.CrtYd")
		)
		(fp_poly
			(pts
				(xy -4.22656 -3.81) (xy 4.22656 -3.81) (xy 4.22656 3.81) (xy -4.22656 3.81)
			)
			(stroke
				(width 0)
				(type default)
			)
			(fill no)
			(layer "F.Fab")
		)
		(pad "1" smd rect
			(at -3.57632 2.8194 270)
			(size 0.3556 1.524)
			(layers "F.Cu" "F.Mask" "F.Paste")
			(net "IO_EXP2_HDD_FAULT_INT_N")
		)
		(pad "2" smd rect
			(at -2.92608 2.8194 270)
			(size 0.3556 1.524)
			(layers "F.Cu" "F.Mask" "F.Paste")
			(net "IO_EXP2_HDD_FAULT_A1")
		)
		(pad "3" smd rect
			(at -2.27584 2.8194 270)
			(size 0.3556 1.524)
			(layers "F.Cu" "F.Mask" "F.Paste")
			(net "IO_EXP2_HDD_FAULT_A2")
		)
		(pad "4" smd rect
			(at -1.6256 2.8194 270)
			(size 0.3556 1.524)
			(layers "F.Cu" "F.Mask" "F.Paste")
			(net "DRIVE_B_16_FLT_LED")
		)
		(pad "5" smd rect
			(at -0.97536 2.8194 270)
			(size 0.3556 1.524)
			(layers "F.Cu" "F.Mask" "F.Paste")
			(net "DRIVE_B_17_FLT_LED")
		)
		(pad "6" smd rect
			(at -0.32512 2.8194 270)
			(size 0.3556 1.524)
			(layers "F.Cu" "F.Mask" "F.Paste")
			(net "DRIVE_B_18_FLT_LED")
		)
		(pad "7" smd rect
			(at 0.32512 2.8194 270)
			(size 0.3556 1.524)
			(layers "F.Cu" "F.Mask" "F.Paste")
			(net "DRIVE_B_19_FLT_LED")
		)
		(pad "8" smd rect
			(at 0.97536 2.8194 270)
			(size 0.3556 1.524)
			(layers "F.Cu" "F.Mask" "F.Paste")
			(net "DRIVE_B_20_FLT_LED")
		)
		(pad "9" smd rect
			(at 1.6256 2.8194 270)
			(size 0.3556 1.524)
			(layers "F.Cu" "F.Mask" "F.Paste")
			(net "DRIVE_B_21_FLT_LED")
		)
		(pad "10" smd rect
			(at 2.27584 2.8194 270)
			(size 0.3556 1.524)
			(layers "F.Cu" "F.Mask" "F.Paste")
			(net "DRIVE_B_22_FLT_LED")
		)
		(pad "11" smd rect
			(at 2.92608 2.8194 270)
			(size 0.3556 1.524)
			(layers "F.Cu" "F.Mask" "F.Paste")
			(net "DRIVE_B_23_FLT_LED")
		)
		(pad "12" smd rect
			(at 3.57632 2.8194 270)
			(size 0.3556 1.524)
			(layers "F.Cu" "F.Mask" "F.Paste")
			(net "GND")
		)
		(pad "13" smd rect
			(at 3.57632 -2.8194 270)
			(size 0.3556 1.524)
			(layers "F.Cu" "F.Mask" "F.Paste")
			(net "RDPB_FAN_LED0")
		)
		(pad "14" smd rect
			(at 2.92608 -2.8194 270)
			(size 0.3556 1.524)
			(layers "F.Cu" "F.Mask" "F.Paste")
			(net "RDPB_FAN_LED1")
		)
		(pad "15" smd rect
			(at 2.27584 -2.8194 270)
			(size 0.3556 1.524)
			(layers "F.Cu" "F.Mask" "F.Paste")
			(net "RDPB_FAN_LED2")
		)
		(pad "16" smd rect
			(at 1.6256 -2.8194 270)
			(size 0.3556 1.524)
			(layers "F.Cu" "F.Mask" "F.Paste")
			(net "RDPB_FAN_LED3")
		)
		(pad "17" smd rect
			(at 0.97536 -2.8194 270)
			(size 0.3556 1.524)
			(layers "F.Cu" "F.Mask" "F.Paste")
			(net "Net_203")
		)
		(pad "18" smd rect
			(at 0.32512 -2.8194 270)
			(size 0.3556 1.524)
			(layers "F.Cu" "F.Mask" "F.Paste")
			(net "Net_204")
		)
		(pad "19" smd rect
			(at -0.32512 -2.8194 270)
			(size 0.3556 1.524)
			(layers "F.Cu" "F.Mask" "F.Paste")
			(net "Net_205")
		)
		(pad "20" smd rect
			(at -0.97536 -2.8194 270)
			(size 0.3556 1.524)
			(layers "F.Cu" "F.Mask" "F.Paste")
			(net "Net_206")
		)
		(pad "21" smd rect
			(at -1.6256 -2.8194 270)
			(size 0.3556 1.524)
			(layers "F.Cu" "F.Mask" "F.Paste")
			(net "IO_EXP2_HDD_FAULT_A0")
		)
		(pad "22" smd rect
			(at -2.27584 -2.8194 270)
			(size 0.3556 1.524)
			(layers "F.Cu" "F.Mask" "F.Paste")
			(net "IO_EXP2_LED_SCL")
		)
		(pad "23" smd rect
			(at -2.92608 -2.8194 270)
			(size 0.3556 1.524)
			(layers "F.Cu" "F.Mask" "F.Paste")
			(net "IO_EXP2_LED_SDA")
		)
		(pad "24" smd rect
			(at -3.57632 -2.8194 270)
			(size 0.3556 1.524)
			(layers "F.Cu" "F.Mask" "F.Paste")
			(net "P3V3_STBY_B")
		)
	)
	(footprint ""
		(layer "F.Cu")
		(at 214.237824 -355.736144 -90)
		(property "Reference" "R1022"
			(at 0 0 270)
			(layer "F.SilkS")
			(hide yes)
			(effects
				(font
					(size 1.27 1.27)
				)
			)
		)
		(property "Value" "0R5J-5-GP"
			(at 0 -8.9535 270)
			(unlocked yes)
			(layer "F.Fab")
			(hide yes)
			(effects
				(font
					(size 1.27 1.016)
					(thickness 0.1524)
				)
			)
		)
		(property "Device Type" "R805H24"
			(at 0 -10.6299 270)
			(unlocked yes)
			(layer "F.Fab")
			(hide yes)
			(effects
				(font
					(size 1.27 1.016)
					(thickness 0.1524)
				)
			)
		)
		(duplicate_pad_numbers_are_jumpers no)
		(fp_line
			(start -0.889 1.7018)
			(end 0.889 1.7018)
			(stroke
				(width 0.1524)
				(type default)
			)
			(layer "F.SilkS")
		)
		(fp_line
			(start 0.889 1.7018)
			(end 0.889 -0.508)
			(stroke
				(width 0.1524)
				(type default)
			)
			(layer "F.SilkS")
		)
		(fp_line
			(start -0.889 0.0762)
			(end -0.889 1.7018)
			(stroke
				(width 0.1524)
				(type default)
			)
			(layer "F.SilkS")
		)
		(fp_line
			(start -0.889 -1.7018)
			(end -0.889 0.2794)
			(stroke
				(width 0.1524)
				(type default)
			)
			(layer "F.SilkS")
		)
		(fp_line
			(start 0.889 -1.7018)
			(end 0.889 -0.381)
			(stroke
				(width 0.1524)
				(type default)
			)
			(layer "F.SilkS")
		)
		(fp_line
			(start 0.889 -1.7018)
			(end -0.889 -1.7018)
			(stroke
				(width 0.1524)
				(type default)
			)
			(layer "F.SilkS")
		)
		(fp_poly
			(pts
				(xy 0.9652 -1.778) (xy 0.9652 1.778) (xy -0.9652 1.778) (xy -0.9652 -1.778)
			)
			(stroke
				(width 0)
				(type default)
			)
			(fill no)
			(layer "F.CrtYd")
		)
		(fp_rect
			(start -0.9652 1.778)
			(end 0.9652 -1.778)
			(stroke
				(width 0)
				(type default)
			)
			(fill no)
			(layer "F.Fab")
		)
		(pad "1" smd rect
			(at 0 -0.9652 270)
			(size 1.397 1.143)
			(layers "F.Cu" "F.Mask" "F.Paste")
			(net "MB0_CM_GATE")
		)
		(pad "2" smd rect
			(at 0 0.9652 270)
			(size 1.397 1.143)
			(layers "F.Cu" "F.Mask" "F.Paste")
			(net "MB0_CM_GATE_R")
		)
	)
	(footprint ""
		(layer "F.Cu")
		(at 320.7004 -31.6484 180)
		(property "Reference" "R760"
			(at 0 0 180)
			(layer "F.SilkS")
			(hide yes)
			(effects
				(font
					(size 1.27 1.27)
				)
			)
		)
		(property "Value" "10KR2F-2-GP"
			(at 0.064008 -3.993896 180)
			(unlocked yes)
			(layer "F.Fab")
			(hide yes)
			(effects
				(font
					(size 1.016 1.016)
					(thickness 0.1524)
				)
			)
		)
		(property "Device Type" "R402H16"
			(at 0.064008 -5.517896 180)
			(unlocked yes)
			(layer "F.Fab")
			(hide yes)
			(effects
				(font
					(size 1.016 1.016)
					(thickness 0.1524)
				)
			)
		)
		(duplicate_pad_numbers_are_jumpers no)
		(fp_line
			(start 0.508 -0.9398)
			(end -0.508 -0.9398)
			(stroke
				(width 0.1524)
				(type default)
			)
			(layer "F.SilkS")
		)
		(fp_line
			(start -0.508 -0.9398)
			(end -0.508 0.9398)
			(stroke
				(width 0.1524)
				(type default)
			)
			(layer "F.SilkS")
		)
		(fp_rect
			(start -0.508 0.9398)
			(end 0.508 -0.9398)
			(stroke
				(width 0)
				(type default)
			)
			(fill no)
			(layer "F.CrtYd")
		)
		(fp_rect
			(start -0.508 0.9398)
			(end 0.508 -0.9398)
			(stroke
				(width 0)
				(type default)
			)
			(fill no)
			(layer "F.Fab")
		)
		(pad "1" smd custom
			(at 0 -0.4445 180)
			(size 0.1397 0.1397)
			(layers "F.Cu" "F.Mask" "F.Paste")
			(net "P3V3_STBY_B")
			(options
				(clearance outline)
				(anchor circle)
			)
			(primitives
				(gr_poly
					(pts
						(arc
							(start -0.1778 -0.2794)
							(mid -0.249642 -0.249642)
							(end -0.2794 -0.1778)
						)
						(arc
							(start -0.2794 0.1778)
							(mid -0.249642 0.249642)
							(end -0.1778 0.2794)
						)
						(arc
							(start 0.1778 0.2794)
							(mid 0.249642 0.249642)
							(end 0.2794 0.1778)
						)
						(arc
							(start 0.2794 -0.1778)
							(mid 0.249642 -0.249642)
							(end 0.1778 -0.2794)
						)
					)
					(width 0)
					(fill yes)
				)
			)
		)
		(pad "2" smd custom
			(at 0 0.4445 180)
			(size 0.1397 0.1397)
			(layers "F.Cu" "F.Mask" "F.Paste")
			(net "HDD_PRSNT_30")
			(options
				(clearance outline)
				(anchor circle)
			)
			(primitives
				(gr_poly
					(pts
						(arc
							(start -0.1778 -0.2794)
							(mid -0.249642 -0.249642)
							(end -0.2794 -0.1778)
						)
						(arc
							(start -0.2794 0.1778)
							(mid -0.249642 0.249642)
							(end -0.1778 0.2794)
						)
						(arc
							(start 0.1778 0.2794)
							(mid 0.249642 0.249642)
							(end 0.2794 0.1778)
						)
						(arc
							(start 0.2794 -0.1778)
							(mid 0.249642 -0.249642)
							(end 0.1778 -0.2794)
						)
					)
					(width 0)
					(fill yes)
				)
			)
		)
	)
	(footprint ""
		(layer "F.Cu")
		(at 50.038 -20.955 90)
		(property "Reference" "C363"
			(at 0 0 90)
			(layer "F.SilkS")
			(hide yes)
			(effects
				(font
					(size 1.27 1.27)
				)
			)
		)
		(property "Value" "SCD033U25V2KX-GP"
			(at 1.1811 -2.7051 90)
			(unlocked yes)
			(layer "F.Fab")
			(hide yes)
			(effects
				(font
					(size 1.016 1.016)
					(thickness 0.1524)
				)
			)
		)
		(property "Device Type" "C402H22"
			(at 1.1811 -4.2291 90)
			(unlocked yes)
			(layer "F.Fab")
			(hide yes)
			(effects
				(font
					(size 1.016 1.016)
					(thickness 0.1524)
				)
			)
		)
		(duplicate_pad_numbers_are_jumpers no)
		(fp_rect
			(start -0.4318 0.9525)
			(end 0.4318 -0.9525)
			(stroke
				(width 0)
				(type default)
			)
			(fill no)
			(layer "F.CrtYd")
		)
		(fp_rect
			(start -0.4318 0.9525)
			(end 0.4318 -0.9525)
			(stroke
				(width 0)
				(type default)
			)
			(fill no)
			(layer "F.Fab")
		)
		(pad "1" smd custom
			(at 0 -0.4445 90)
			(size 0.1524 0.1524)
			(layers "F.Cu" "F.Mask" "F.Paste")
			(net "SW_HDD_P25")
			(options
				(clearance outline)
				(anchor circle)
			)
			(primitives
				(gr_poly
					(pts
						(arc
							(start 0.3048 -0.2032)
							(mid 0.275042 -0.275042)
							(end 0.2032 -0.3048)
						)
						(arc
							(start -0.2032 -0.3048)
							(mid -0.275042 -0.275042)
							(end -0.3048 -0.2032)
						)
						(arc
							(start -0.3048 0.2032)
							(mid -0.275042 0.275042)
							(end -0.2032 0.3048)
						)
						(arc
							(start 0.2032 0.3048)
							(mid 0.275042 0.275042)
							(end 0.3048 0.2032)
						)
					)
					(width 0)
					(fill yes)
				)
			)
		)
		(pad "2" smd custom
			(at 0 0.4445 90)
			(size 0.1524 0.1524)
			(layers "F.Cu" "F.Mask" "F.Paste")
			(net "GND")
			(options
				(clearance outline)
				(anchor circle)
			)
			(primitives
				(gr_poly
					(pts
						(arc
							(start 0.3048 -0.2032)
							(mid 0.275042 -0.275042)
							(end 0.2032 -0.3048)
						)
						(arc
							(start -0.2032 -0.3048)
							(mid -0.275042 -0.275042)
							(end -0.3048 -0.2032)
						)
						(arc
							(start -0.3048 0.2032)
							(mid -0.275042 0.275042)
							(end -0.2032 0.3048)
						)
						(arc
							(start 0.2032 0.3048)
							(mid 0.275042 0.275042)
							(end 0.3048 0.2032)
						)
					)
					(width 0)
					(fill yes)
				)
			)
		)
	)
	(footprint ""
		(layer "F.Cu")
		(at 95.608902 -18.750026 -90)
		(property "Reference" "VIA54"
			(at 0 0 270)
			(layer "F.SilkS")
			(hide yes)
			(effects
				(font
					(size 1.27 1.27)
				)
			)
		)
		(property "Value" "100OHM-8L-2D36MM-L16-GP"
			(at -3.4036 -0.4572 270)
			(unlocked yes)
			(layer "F.Fab")
			(hide yes)
			(effects
				(font
					(size 1.016 1.016)
					(thickness 0.1524)
				)
			)
		)
		(property "Device Type" "VIA-PCIE-4P-427097"
			(at -3.4036 -1.9812 270)
			(unlocked yes)
			(layer "F.Fab")
			(hide yes)
			(effects
				(font
					(size 1.016 1.016)
					(thickness 0.1524)
				)
			)
		)
		(duplicate_pad_numbers_are_jumpers no)
		(fp_rect
			(start -2.1336 0.4826)
			(end 2.1336 -0.4826)
			(stroke
				(width 0)
				(type default)
			)
			(fill no)
			(layer "F.CrtYd")
		)
		(fp_rect
			(start -2.1336 0.4826)
			(end 2.1336 -0.4826)
			(stroke
				(width 0)
				(type default)
			)
			(fill no)
			(layer "F.Fab")
		)
		(pad "1" thru_hole circle
			(at -1.651 0 270)
			(size 0.508 0.508)
			(drill 0.254)
			(layers "*.Cu" "*.Mask")
			(remove_unused_layers no)
			(net "GND")
			(clearance 0.2286)
			(thermal_gap 0.2286)
		)
		(pad "2" thru_hole circle
			(at -0.635 0 270)
			(size 0.508 0.508)
			(drill 0.254)
			(layers "*.Cu" "*.Mask")
			(remove_unused_layers no)
			(net "PHY_DRV_B_TO_SCC_B_26_DP")
			(clearance 0.2286)
			(thermal_gap 0.2286)
		)
		(pad "3" thru_hole circle
			(at 0.635 0 270)
			(size 0.508 0.508)
			(drill 0.254)
			(layers "*.Cu" "*.Mask")
			(remove_unused_layers no)
			(net "PHY_DRV_B_TO_SCC_B_26_DN")
			(clearance 0.2286)
			(thermal_gap 0.2286)
		)
		(pad "4" thru_hole circle
			(at 1.651 0 270)
			(size 0.508 0.508)
			(drill 0.254)
			(layers "*.Cu" "*.Mask")
			(remove_unused_layers no)
			(net "GND")
			(clearance 0.2286)
			(thermal_gap 0.2286)
		)
	)
	(footprint ""
		(layer "F.Cu")
		(at 350.766126 -269.705074)
		(property "Reference" "TP56"
			(at 0 0 0)
			(layer "F.SilkS")
			(hide yes)
			(effects
				(font
					(size 1.27 1.27)
				)
			)
		)
		(property "Value" "*"
			(at -0.0508 -1.6764 0)
			(unlocked yes)
			(layer "F.Fab")
			(hide yes)
			(effects
				(font
					(size 1.016 1.016)
					(thickness 0.1524)
				)
			)
		)
		(property "Device Type" "TPAD32"
			(at -0.0508 -3.2004 0)
			(unlocked yes)
			(layer "F.Fab")
			(hide yes)
			(effects
				(font
					(size 1.016 1.016)
					(thickness 0.1524)
				)
			)
		)
		(duplicate_pad_numbers_are_jumpers no)
		(fp_poly
			(pts
				(arc
					(start 0.4064 0)
					(mid -0.4064 0)
					(end 0.4064 0)
				)
			)
			(stroke
				(width 0)
				(type default)
			)
			(fill no)
			(layer "F.CrtYd")
		)
		(fp_poly
			(pts
				(arc
					(start 0.7112 0)
					(mid -0.7112 0)
					(end 0.7112 0)
				)
			)
			(stroke
				(width 0)
				(type default)
			)
			(fill no)
			(layer "F.Fab")
		)
		(pad "1" smd circle
			(at 0 0)
			(size 0.8128 0.8128)
			(layers "F.Cu" "F.Mask" "F.Paste")
			(net "ACT_HDD_7")
		)
	)
	(footprint ""
		(layer "F.Cu")
		(at 368.808 -248.793 90)
		(property "Reference" "D7"
			(at 0 0 90)
			(layer "F.SilkS")
			(hide yes)
			(effects
				(font
					(size 1.27 1.27)
				)
			)
		)
		(property "Value" "RB551V30-GP"
			(at 0 -6.7818 90)
			(unlocked yes)
			(layer "F.Fab")
			(hide yes)
			(effects
				(font
					(size 1.016 1.016)
					(thickness 0.1524)
				)
			)
		)
		(property "Device Type" "SOD323AKH38"
			(at 0 -8.6868 90)
			(unlocked yes)
			(layer "F.Fab")
			(hide yes)
			(effects
				(font
					(size 1.016 1.016)
					(thickness 0.1524)
				)
			)
		)
		(duplicate_pad_numbers_are_jumpers no)
		(fp_line
			(start 0.889 -1.9304)
			(end 0.889 2.159)
			(stroke
				(width 0.1524)
				(type default)
			)
			(layer "F.SilkS")
		)
		(fp_line
			(start -0.889 -1.9304)
			(end 0.889 -1.9304)
			(stroke
				(width 0.1524)
				(type default)
			)
			(layer "F.SilkS")
		)
		(fp_line
			(start 0.762 2.0574)
			(end -0.762 2.0574)
			(stroke
				(width 0.508)
				(type default)
			)
			(layer "F.SilkS")
		)
		(fp_line
			(start 0.889 2.159)
			(end -0.889 2.159)
			(stroke
				(width 0.1524)
				(type default)
			)
			(layer "F.SilkS")
		)
		(fp_line
			(start -0.889 2.159)
			(end -0.889 -1.9304)
			(stroke
				(width 0.1524)
				(type default)
			)
			(layer "F.SilkS")
		)
		(fp_rect
			(start -1.016 2.3114)
			(end 1.016 -2.0066)
			(stroke
				(width 0)
				(type default)
			)
			(fill no)
			(layer "F.CrtYd")
		)
		(fp_poly
			(pts
				(xy -1.016 -2.0066) (xy 1.016 -2.0066) (xy 1.016 2.3114) (xy -1.016 2.3114)
			)
			(stroke
				(width 0)
				(type default)
			)
			(fill no)
			(layer "F.Fab")
		)
		(pad "A" smd rect
			(at 0 -1.143 90)
			(size 0.5588 1.016)
			(layers "F.Cu" "F.Mask" "F.Paste")
			(net "SW_HDD_R7")
		)
		(pad "K" smd rect
			(at 0 1.143 90)
			(size 0.5588 1.016)
			(layers "F.Cu" "F.Mask" "F.Paste")
			(net "SW_HDD_N7")
		)
	)
)
